(kicad_pcb
	(version 20260206)
	(generator "pcbnew")
	(generator_version "10.0")
	(general
		(thickness 1.6)
		(legacy_teardrops no)
	)
	(paper "A4")
	(title_block
		(title "04192023_DAF0TMB3IC0_F0TG_MB_C_brd_V02_OCP.brd")
		(comment 1 "Grand Teton / footprints 7209-7214 of 8354")
	)
	(layers
		(0 "F.Cu" signal "TOP")
		(4 "In1.Cu" signal "GND")
		(6 "In2.Cu" signal "IN1")
		(8 "In3.Cu" signal "GND1")
		(10 "In4.Cu" signal "IN2")
		(12 "In5.Cu" signal "GND2")
		(14 "In6.Cu" signal "IN3")
		(16 "In7.Cu" signal "GND3")
		(18 "In8.Cu" signal "VCC")
		(20 "In9.Cu" signal "VCC1")
		(22 "In10.Cu" signal "GND4")
		(24 "In11.Cu" signal "IN4")
		(26 "In12.Cu" signal "GND5")
		(28 "In13.Cu" signal "IN5")
		(30 "In14.Cu" signal "GND6")
		(32 "In15.Cu" signal "IN6")
		(34 "In16.Cu" signal "GND7")
		(2 "B.Cu" signal "BOTTOM")
		(9 "F.Adhes" user "F.Adhesive")
		(11 "B.Adhes" user "B.Adhesive")
		(13 "F.Paste" user "Package Geometry/Pastemask Top")
		(15 "B.Paste" user "Package Geometry/Pastemask Bottom")
		(5 "F.SilkS" user "Ref Des/Silkscreen Top")
		(7 "B.SilkS" user "Ref Des/Silkscreen Bottom")
		(1 "F.Mask" user "Board Geometry/Soldermask Top")
		(3 "B.Mask" user "Board Geometry/Soldermask Bottom")
		(17 "Dwgs.User" user "User.Drawings")
		(19 "Cmts.User" user "User.Comments")
		(21 "Eco1.User" user "User.Eco1")
		(23 "Eco2.User" user "User.Eco2")
		(25 "Edge.Cuts" user "Board Geometry/Outline")
		(27 "Margin" user)
		(31 "F.CrtYd" user "Package Geometry/Place Bound Top")
		(29 "B.CrtYd" user "Package Geometry/Place Bound Bottom")
		(35 "F.Fab" user "Ref Des/Assembly Top")
		(33 "B.Fab" user "Ref Des/Assembly Bottom")
	)
	(footprint ""
		(layer "B.Cu")
		(at 442.290454 -191.20231 180)
		(property "Reference" "R301"
			(at 0 0 0)
			(layer "B.SilkS")
			(hide yes)
			(effects
				(font
					(size 1.27 1.27)
				)
				(justify mirror)
			)
		)
		(property "Value" ""
			(at 0 0 0)
			(layer "B.Fab")
			(effects
				(font
					(size 1.27 1.27)
				)
				(justify mirror)
			)
		)
		(duplicate_pad_numbers_are_jumpers no)
		(fp_line
			(start 0.7874 0.4064)
			(end 0.7874 -0.4064)
			(stroke
				(width 0.1524)
				(type default)
			)
			(layer "B.SilkS")
		)
		(fp_line
			(start 0.7874 -0.4064)
			(end -0.7874 -0.4064)
			(stroke
				(width 0.1524)
				(type default)
			)
			(layer "B.SilkS")
		)
		(fp_line
			(start -0.7874 0.4064)
			(end 0.7874 0.4064)
			(stroke
				(width 0.1524)
				(type default)
			)
			(layer "B.SilkS")
		)
		(fp_line
			(start -0.7874 -0.4064)
			(end -0.7874 0.4064)
			(stroke
				(width 0.1524)
				(type default)
			)
			(layer "B.SilkS")
		)
		(fp_line
			(start 0.67945 0.3048)
			(end 0.67945 -0.305054)
			(stroke
				(width 0.1)
				(type default)
			)
			(layer "B.Fab")
		)
		(fp_line
			(start 0.67945 -0.305054)
			(end 0.12065 -0.305054)
			(stroke
				(width 0.1)
				(type default)
			)
			(layer "B.Fab")
		)
		(fp_line
			(start 0.12065 0.3048)
			(end 0.67945 0.3048)
			(stroke
				(width 0.1)
				(type default)
			)
			(layer "B.Fab")
		)
		(fp_line
			(start 0.12065 0.2794)
			(end 0.12065 0.3048)
			(stroke
				(width 0.1)
				(type default)
			)
			(layer "B.Fab")
		)
		(fp_line
			(start 0.12065 -0.2794)
			(end -0.12065 -0.2794)
			(stroke
				(width 0.1)
				(type default)
			)
			(layer "B.Fab")
		)
		(fp_line
			(start 0.12065 -0.305054)
			(end 0.12065 -0.2794)
			(stroke
				(width 0.1)
				(type default)
			)
			(layer "B.Fab")
		)
		(fp_line
			(start -0.120396 0.3048)
			(end -0.120396 0.2794)
			(stroke
				(width 0.1)
				(type default)
			)
			(layer "B.Fab")
		)
		(fp_line
			(start -0.120396 0.2794)
			(end 0.12065 0.2794)
			(stroke
				(width 0.1)
				(type default)
			)
			(layer "B.Fab")
		)
		(fp_line
			(start -0.12065 -0.2794)
			(end -0.12065 -0.3048)
			(stroke
				(width 0.1)
				(type default)
			)
			(layer "B.Fab")
		)
		(fp_line
			(start -0.12065 -0.3048)
			(end -0.67945 -0.3048)
			(stroke
				(width 0.1)
				(type default)
			)
			(layer "B.Fab")
		)
		(fp_line
			(start -0.67945 0.3048)
			(end -0.120396 0.3048)
			(stroke
				(width 0.1)
				(type default)
			)
			(layer "B.Fab")
		)
		(fp_line
			(start -0.67945 -0.3048)
			(end -0.67945 0.3048)
			(stroke
				(width 0.1)
				(type default)
			)
			(layer "B.Fab")
		)
		(pad "1" smd circle
			(at 0.40005 0)
			(size 0 0)
			(layers "B.Cu" "B.Mask" "B.Paste")
			(net "PWRGD_CHK_CPU0_DIMM")
		)
		(pad "2" smd circle
			(at -0.40005 0)
			(size 0 0)
			(layers "B.Cu" "B.Mask" "B.Paste")
			(net "PWRGD_CHGL_CPU0")
		)
	)
	(footprint ""
		(layer "B.Cu")
		(at 372.937278 -139.440158)
		(property "Reference" "C467"
			(at 0 0 0)
			(layer "B.SilkS")
			(hide yes)
			(effects
				(font
					(size 1.27 1.27)
				)
				(justify mirror)
			)
		)
		(property "Value" ""
			(at 0 0 0)
			(layer "B.Fab")
			(effects
				(font
					(size 1.27 1.27)
				)
				(justify mirror)
			)
		)
		(duplicate_pad_numbers_are_jumpers no)
		(fp_line
			(start -0.7874 -0.4064)
			(end -0.7874 0.4064)
			(stroke
				(width 0.1524)
				(type default)
			)
			(layer "B.SilkS")
		)
		(fp_line
			(start -0.7874 0.4064)
			(end 0.7874 0.4064)
			(stroke
				(width 0.1524)
				(type default)
			)
			(layer "B.SilkS")
		)
		(fp_line
			(start 0.7874 -0.4064)
			(end -0.7874 -0.4064)
			(stroke
				(width 0.1524)
				(type default)
			)
			(layer "B.SilkS")
		)
		(fp_line
			(start 0.7874 0.4064)
			(end 0.7874 -0.4064)
			(stroke
				(width 0.1524)
				(type default)
			)
			(layer "B.SilkS")
		)
		(fp_line
			(start -0.67945 -0.3048)
			(end -0.67945 0.3048)
			(stroke
				(width 0.1)
				(type default)
			)
			(layer "B.Fab")
		)
		(fp_line
			(start -0.67945 0.3048)
			(end -0.120396 0.3048)
			(stroke
				(width 0.1)
				(type default)
			)
			(layer "B.Fab")
		)
		(fp_line
			(start -0.12065 -0.3048)
			(end -0.67945 -0.3048)
			(stroke
				(width 0.1)
				(type default)
			)
			(layer "B.Fab")
		)
		(fp_line
			(start -0.12065 -0.2794)
			(end -0.12065 -0.3048)
			(stroke
				(width 0.1)
				(type default)
			)
			(layer "B.Fab")
		)
		(fp_line
			(start -0.120396 0.2794)
			(end 0.12065 0.2794)
			(stroke
				(width 0.1)
				(type default)
			)
			(layer "B.Fab")
		)
		(fp_line
			(start -0.120396 0.3048)
			(end -0.120396 0.2794)
			(stroke
				(width 0.1)
				(type default)
			)
			(layer "B.Fab")
		)
		(fp_line
			(start 0.12065 -0.305054)
			(end 0.12065 -0.2794)
			(stroke
				(width 0.1)
				(type default)
			)
			(layer "B.Fab")
		)
		(fp_line
			(start 0.12065 -0.2794)
			(end -0.12065 -0.2794)
			(stroke
				(width 0.1)
				(type default)
			)
			(layer "B.Fab")
		)
		(fp_line
			(start 0.12065 0.2794)
			(end 0.12065 0.3048)
			(stroke
				(width 0.1)
				(type default)
			)
			(layer "B.Fab")
		)
		(fp_line
			(start 0.12065 0.3048)
			(end 0.67945 0.3048)
			(stroke
				(width 0.1)
				(type default)
			)
			(layer "B.Fab")
		)
		(fp_line
			(start 0.67945 -0.305054)
			(end 0.12065 -0.305054)
			(stroke
				(width 0.1)
				(type default)
			)
			(layer "B.Fab")
		)
		(fp_line
			(start 0.67945 0.3048)
			(end 0.67945 -0.305054)
			(stroke
				(width 0.1)
				(type default)
			)
			(layer "B.Fab")
		)
		(pad "1" smd circle
			(at 0.40005 0 180)
			(size 0 0)
			(layers "B.Cu" "B.Mask" "B.Paste")
			(net "PWRGD_PVDDCR_CPU0_P0_R")
		)
		(pad "2" smd circle
			(at -0.40005 0 180)
			(size 0 0)
			(layers "B.Cu" "B.Mask" "B.Paste")
			(net "GND")
		)
	)
	(footprint ""
		(layer "B.Cu")
		(at 152.265634 -201.977752 -90)
		(property "Reference" "C233"
			(at 0 0 90)
			(layer "B.SilkS")
			(hide yes)
			(effects
				(font
					(size 1.27 1.27)
				)
				(justify mirror)
			)
		)
		(property "Value" ""
			(at 0 0 90)
			(layer "B.Fab")
			(effects
				(font
					(size 1.27 1.27)
				)
				(justify mirror)
			)
		)
		(duplicate_pad_numbers_are_jumpers no)
		(fp_line
			(start -0.7874 0.4064)
			(end 0.7874 0.4064)
			(stroke
				(width 0.1524)
				(type default)
			)
			(layer "B.SilkS")
		)
		(fp_line
			(start 0.7874 0.4064)
			(end 0.7874 -0.4064)
			(stroke
				(width 0.1524)
				(type default)
			)
			(layer "B.SilkS")
		)
		(fp_line
			(start -0.7874 -0.4064)
			(end -0.7874 0.4064)
			(stroke
				(width 0.1524)
				(type default)
			)
			(layer "B.SilkS")
		)
		(fp_line
			(start 0.7874 -0.4064)
			(end -0.7874 -0.4064)
			(stroke
				(width 0.1524)
				(type default)
			)
			(layer "B.SilkS")
		)
		(fp_line
			(start -0.67945 0.3048)
			(end -0.120396 0.3048)
			(stroke
				(width 0.1)
				(type default)
			)
			(layer "B.Fab")
		)
		(fp_line
			(start -0.120396 0.3048)
			(end -0.120396 0.2794)
			(stroke
				(width 0.1)
				(type default)
			)
			(layer "B.Fab")
		)
		(fp_line
			(start 0.12065 0.3048)
			(end 0.67945 0.3048)
			(stroke
				(width 0.1)
				(type default)
			)
			(layer "B.Fab")
		)
		(fp_line
			(start 0.67945 0.3048)
			(end 0.67945 -0.305054)
			(stroke
				(width 0.1)
				(type default)
			)
			(layer "B.Fab")
		)
		(fp_line
			(start -0.120396 0.2794)
			(end 0.12065 0.2794)
			(stroke
				(width 0.1)
				(type default)
			)
			(layer "B.Fab")
		)
		(fp_line
			(start 0.12065 0.2794)
			(end 0.12065 0.3048)
			(stroke
				(width 0.1)
				(type default)
			)
			(layer "B.Fab")
		)
		(fp_line
			(start -0.12065 -0.2794)
			(end -0.12065 -0.3048)
			(stroke
				(width 0.1)
				(type default)
			)
			(layer "B.Fab")
		)
		(fp_line
			(start 0.12065 -0.2794)
			(end -0.12065 -0.2794)
			(stroke
				(width 0.1)
				(type default)
			)
			(layer "B.Fab")
		)
		(fp_line
			(start -0.67945 -0.3048)
			(end -0.67945 0.3048)
			(stroke
				(width 0.1)
				(type default)
			)
			(layer "B.Fab")
		)
		(fp_line
			(start -0.12065 -0.3048)
			(end -0.67945 -0.3048)
			(stroke
				(width 0.1)
				(type default)
			)
			(layer "B.Fab")
		)
		(fp_line
			(start 0.12065 -0.305054)
			(end 0.12065 -0.2794)
			(stroke
				(width 0.1)
				(type default)
			)
			(layer "B.Fab")
		)
		(fp_line
			(start 0.67945 -0.305054)
			(end 0.12065 -0.305054)
			(stroke
				(width 0.1)
				(type default)
			)
			(layer "B.Fab")
		)
		(pad "1" smd circle
			(at 0.40005 0 90)
			(size 0 0)
			(layers "B.Cu" "B.Mask" "B.Paste")
			(net "JTAG_CPU1_TCK")
		)
		(pad "2" smd circle
			(at -0.40005 0 90)
			(size 0 0)
			(layers "B.Cu" "B.Mask" "B.Paste")
			(net "GND")
		)
	)
	(footprint ""
		(layer "B.Cu")
		(at 194.604132 -192.66027 180)
		(property "Reference" "C547"
			(at 0 0 0)
			(layer "B.SilkS")
			(hide yes)
			(effects
				(font
					(size 1.27 1.27)
				)
				(justify mirror)
			)
		)
		(property "Value" ""
			(at 0 0 0)
			(layer "B.Fab")
			(effects
				(font
					(size 1.27 1.27)
				)
				(justify mirror)
			)
		)
		(duplicate_pad_numbers_are_jumpers no)
		(fp_line
			(start 1.524 0.762)
			(end 1.524 -0.762)
			(stroke
				(width 0.1524)
				(type default)
			)
			(layer "B.SilkS")
		)
		(fp_line
			(start 1.524 -0.762)
			(end -1.524 -0.762)
			(stroke
				(width 0.1524)
				(type default)
			)
			(layer "B.SilkS")
		)
		(fp_line
			(start -1.524 0.762)
			(end 1.524 0.762)
			(stroke
				(width 0.1524)
				(type default)
			)
			(layer "B.SilkS")
		)
		(fp_line
			(start -1.524 -0.762)
			(end -1.524 0.762)
			(stroke
				(width 0.1524)
				(type default)
			)
			(layer "B.SilkS")
		)
		(fp_line
			(start 1.1049 0.724916)
			(end -1.1049 0.724916)
			(stroke
				(width 0.1)
				(type default)
			)
			(layer "B.Fab")
		)
		(fp_line
			(start 1.1049 -0.724916)
			(end 1.1049 0.724916)
			(stroke
				(width 0.1)
				(type default)
			)
			(layer "B.Fab")
		)
		(fp_line
			(start -1.1049 0.724916)
			(end -1.1049 -0.724916)
			(stroke
				(width 0.1)
				(type default)
			)
			(layer "B.Fab")
		)
		(fp_line
			(start -1.1049 -0.724916)
			(end 1.1049 -0.724916)
			(stroke
				(width 0.1)
				(type default)
			)
			(layer "B.Fab")
		)
		(pad "1" smd rect
			(at 0.889 0 180)
			(size 1.016 1.27)
			(layers "B.Cu" "B.Mask" "B.Paste")
			(net "P12V_MEM_CPU1")
		)
		(pad "2" smd rect
			(at -0.889 0 180)
			(size 1.016 1.27)
			(layers "B.Cu" "B.Mask" "B.Paste")
			(net "GND")
		)
	)
	(footprint ""
		(layer "B.Cu")
		(at 314.475876 -66.708782 90)
		(property "Reference" "R3102"
			(at 0 0 90)
			(layer "B.SilkS")
			(hide yes)
			(effects
				(font
					(size 1.27 1.27)
				)
				(justify mirror)
			)
		)
		(property "Value" ""
			(at 0 0 90)
			(layer "B.Fab")
			(effects
				(font
					(size 1.27 1.27)
				)
				(justify mirror)
			)
		)
		(duplicate_pad_numbers_are_jumpers no)
		(fp_line
			(start 0.7874 -0.4064)
			(end -0.7874 -0.4064)
			(stroke
				(width 0.1524)
				(type default)
			)
			(layer "B.SilkS")
		)
		(fp_line
			(start -0.7874 -0.4064)
			(end -0.7874 0.4064)
			(stroke
				(width 0.1524)
				(type default)
			)
			(layer "B.SilkS")
		)
		(fp_line
			(start 0.7874 0.4064)
			(end 0.7874 -0.4064)
			(stroke
				(width 0.1524)
				(type default)
			)
			(layer "B.SilkS")
		)
		(fp_line
			(start -0.7874 0.4064)
			(end 0.7874 0.4064)
			(stroke
				(width 0.1524)
				(type default)
			)
			(layer "B.SilkS")
		)
		(fp_line
			(start 0.67945 -0.305054)
			(end 0.12065 -0.305054)
			(stroke
				(width 0.1)
				(type default)
			)
			(layer "B.Fab")
		)
		(fp_line
			(start 0.12065 -0.305054)
			(end 0.12065 -0.2794)
			(stroke
				(width 0.1)
				(type default)
			)
			(layer "B.Fab")
		)
		(fp_line
			(start -0.12065 -0.3048)
			(end -0.67945 -0.3048)
			(stroke
				(width 0.1)
				(type default)
			)
			(layer "B.Fab")
		)
		(fp_line
			(start -0.67945 -0.3048)
			(end -0.67945 0.3048)
			(stroke
				(width 0.1)
				(type default)
			)
			(layer "B.Fab")
		)
		(fp_line
			(start 0.12065 -0.2794)
			(end -0.12065 -0.2794)
			(stroke
				(width 0.1)
				(type default)
			)
			(layer "B.Fab")
		)
		(fp_line
			(start -0.12065 -0.2794)
			(end -0.12065 -0.3048)
			(stroke
				(width 0.1)
				(type default)
			)
			(layer "B.Fab")
		)
		(fp_line
			(start 0.12065 0.2794)
			(end 0.12065 0.3048)
			(stroke
				(width 0.1)
				(type default)
			)
			(layer "B.Fab")
		)
		(fp_line
			(start -0.120396 0.2794)
			(end 0.12065 0.2794)
			(stroke
				(width 0.1)
				(type default)
			)
			(layer "B.Fab")
		)
		(fp_line
			(start 0.67945 0.3048)
			(end 0.67945 -0.305054)
			(stroke
				(width 0.1)
				(type default)
			)
			(layer "B.Fab")
		)
		(fp_line
			(start 0.12065 0.3048)
			(end 0.67945 0.3048)
			(stroke
				(width 0.1)
				(type default)
			)
			(layer "B.Fab")
		)
		(fp_line
			(start -0.120396 0.3048)
			(end -0.120396 0.2794)
			(stroke
				(width 0.1)
				(type default)
			)
			(layer "B.Fab")
		)
		(fp_line
			(start -0.67945 0.3048)
			(end -0.120396 0.3048)
			(stroke
				(width 0.1)
				(type default)
			)
			(layer "B.Fab")
		)
		(pad "1" smd circle
			(at 0.40005 0 270)
			(size 0 0)
			(layers "B.Cu" "B.Mask" "B.Paste")
			(net "LED_P5V")
		)
		(pad "2" smd circle
			(at -0.40005 0 270)
			(size 0 0)
			(layers "B.Cu" "B.Mask" "B.Paste")
			(net "P5V")
		)
	)
	(footprint ""
		(layer "B.Cu")
		(at 162.618928 -390.560052 90)
		(property "Reference" "C424"
			(at 0 0 90)
			(layer "B.SilkS")
			(hide yes)
			(effects
				(font
					(size 1.27 1.27)
				)
				(justify mirror)
			)
		)
		(property "Value" ""
			(at 0 0 90)
			(layer "B.Fab")
			(effects
				(font
					(size 1.27 1.27)
				)
				(justify mirror)
			)
		)
		(duplicate_pad_numbers_are_jumpers no)
		(fp_line
			(start 0.7874 -0.4064)
			(end -0.7874 -0.4064)
			(stroke
				(width 0.1524)
				(type default)
			)
			(layer "B.SilkS")
		)
		(fp_line
			(start -0.7874 -0.4064)
			(end -0.7874 0.4064)
			(stroke
				(width 0.1524)
				(type default)
			)
			(layer "B.SilkS")
		)
		(fp_line
			(start 0.7874 0.4064)
			(end 0.7874 -0.4064)
			(stroke
				(width 0.1524)
				(type default)
			)
			(layer "B.SilkS")
		)
		(fp_line
			(start -0.7874 0.4064)
			(end 0.7874 0.4064)
			(stroke
				(width 0.1524)
				(type default)
			)
			(layer "B.SilkS")
		)
		(fp_line
			(start 0.67945 -0.305054)
			(end 0.12065 -0.305054)
			(stroke
				(width 0.1)
				(type default)
			)
			(layer "B.Fab")
		)
		(fp_line
			(start 0.12065 -0.305054)
			(end 0.12065 -0.2794)
			(stroke
				(width 0.1)
				(type default)
			)
			(layer "B.Fab")
		)
		(fp_line
			(start -0.12065 -0.3048)
			(end -0.67945 -0.3048)
			(stroke
				(width 0.1)
				(type default)
			)
			(layer "B.Fab")
		)
		(fp_line
			(start -0.67945 -0.3048)
			(end -0.67945 0.3048)
			(stroke
				(width 0.1)
				(type default)
			)
			(layer "B.Fab")
		)
		(fp_line
			(start 0.12065 -0.2794)
			(end -0.12065 -0.2794)
			(stroke
				(width 0.1)
				(type default)
			)
			(layer "B.Fab")
		)
		(fp_line
			(start -0.12065 -0.2794)
			(end -0.12065 -0.3048)
			(stroke
				(width 0.1)
				(type default)
			)
			(layer "B.Fab")
		)
		(fp_line
			(start 0.12065 0.2794)
			(end 0.12065 0.3048)
			(stroke
				(width 0.1)
				(type default)
			)
			(layer "B.Fab")
		)
		(fp_line
			(start -0.120396 0.2794)
			(end 0.12065 0.2794)
			(stroke
				(width 0.1)
				(type default)
			)
			(layer "B.Fab")
		)
		(fp_line
			(start 0.67945 0.3048)
			(end 0.67945 -0.305054)
			(stroke
				(width 0.1)
				(type default)
			)
			(layer "B.Fab")
		)
		(fp_line
			(start 0.12065 0.3048)
			(end 0.67945 0.3048)
			(stroke
				(width 0.1)
				(type default)
			)
			(layer "B.Fab")
		)
		(fp_line
			(start -0.120396 0.3048)
			(end -0.120396 0.2794)
			(stroke
				(width 0.1)
				(type default)
			)
			(layer "B.Fab")
		)
		(fp_line
			(start -0.67945 0.3048)
			(end -0.120396 0.3048)
			(stroke
				(width 0.1)
				(type default)
			)
			(layer "B.Fab")
		)
		(pad "1" smd circle
			(at 0.40005 0 270)
			(size 0 0)
			(layers "B.Cu" "B.Mask" "B.Paste")
			(net "P0V9_CPU1_RT2_2A")
		)
		(pad "2" smd circle
			(at -0.40005 0 270)
			(size 0 0)
			(layers "B.Cu" "B.Mask" "B.Paste")
			(net "GND")
		)
	)
)
